(kicad_pcb
	(version 20260206)
	(generator "pcbnew")
	(generator_version "10.0")
	(general
		(thickness 1.6)
		(legacy_teardrops no)
	)
	(paper "A4")
	(title_block
		(title "Wiwynn_Tioga_Pass_MB.brd")
		(comment 1 "Tioga Pass / footprints 1254-1260 of 4770")
	)
	(layers
		(0 "F.Cu" signal "TOP")
		(4 "In1.Cu" signal "L2GND")
		(6 "In2.Cu" signal "L3")
		(8 "In3.Cu" signal "L4GND")
		(10 "In4.Cu" signal "L5")
		(12 "In5.Cu" signal "L6GND")
		(14 "In6.Cu" signal "L7VCC")
		(16 "In7.Cu" signal "L8VCC")
		(18 "In8.Cu" signal "L9GND")
		(20 "In9.Cu" signal "L10")
		(22 "In10.Cu" signal "L11GND")
		(24 "In11.Cu" signal "L12")
		(26 "In12.Cu" signal "L13GND")
		(2 "B.Cu" signal "BOTTOM")
		(9 "F.Adhes" user "F.Adhesive")
		(11 "B.Adhes" user "B.Adhesive")
		(13 "F.Paste" user "Package Geometry/Pastemask Top")
		(15 "B.Paste" user "Package Geometry/Pastemask Bottom")
		(5 "F.SilkS" user "Ref Des/Silkscreen Top")
		(7 "B.SilkS" user "Ref Des/Silkscreen Bottom")
		(1 "F.Mask" user "Board Geometry/Soldermask Top")
		(3 "B.Mask" user "Board Geometry/Soldermask Bottom")
		(17 "Dwgs.User" user "User.Drawings")
		(19 "Cmts.User" user "User.Comments")
		(21 "Eco1.User" user "User.Eco1")
		(23 "Eco2.User" user "User.Eco2")
		(25 "Edge.Cuts" user "Board Geometry/Outline")
		(27 "Margin" user)
		(31 "F.CrtYd" user "Package Geometry/Place Bound Top")
		(29 "B.CrtYd" user "Package Geometry/Place Bound Bottom")
		(35 "F.Fab" user "Ref Des/Assembly Top")
		(33 "B.Fab" user "Ref Des/Assembly Bottom")
	)
	(footprint ""
		(layer "F.Cu")
		(at 25.908 -75.819 -90)
		(property "Reference" "R1D35"
			(at 0 0 270)
			(layer "F.SilkS")
			(hide yes)
			(effects
				(font
					(size 1.27 1.27)
				)
			)
		)
		(property "Value" ""
			(at 0 0 270)
			(layer "F.Fab")
			(effects
				(font
					(size 1.27 1.27)
				)
			)
		)
		(duplicate_pad_numbers_are_jumpers no)
		(fp_poly
			(pts
				(xy -0.2794 -0.1016) (xy 0.2794 -0.1016) (xy 0.2794 0.9906) (xy -0.2794 0.9906)
			)
			(stroke
				(width 0)
				(type default)
			)
			(fill no)
			(layer "F.CrtYd")
		)
		(fp_line
			(start -0.2794 0.9906)
			(end 0.2794 0.9906)
			(stroke
				(width 0.1)
				(type default)
			)
			(layer "F.Fab")
		)
		(fp_line
			(start 0.2794 0.9906)
			(end 0.2794 -0.1016)
			(stroke
				(width 0.1)
				(type default)
			)
			(layer "F.Fab")
		)
		(fp_line
			(start -0.2794 -0.1016)
			(end -0.2794 0.9906)
			(stroke
				(width 0.1)
				(type default)
			)
			(layer "F.Fab")
		)
		(fp_line
			(start 0.2794 -0.1016)
			(end -0.2794 -0.1016)
			(stroke
				(width 0.1)
				(type default)
			)
			(layer "F.Fab")
		)
		(pad "1" smd rect
			(at 0 0 270)
			(size 0.508 0.508)
			(layers "F.Cu" "F.Mask" "F.Paste")
			(net "P3V3_STBY")
		)
		(pad "2" smd rect
			(at 0 0.889 270)
			(size 0.508 0.508)
			(layers "F.Cu" "F.Mask" "F.Paste")
			(net "FM_OC_DETECT_EN_N")
		)
		(zone
			(layer "F.Cu")
			(hatch none 0.5)
			(connect_pads
				(clearance 0)
			)
			(min_thickness 0.25)
			(keepout
				(tracks not_allowed)
				(vias allowed)
				(pads allowed)
				(copperpour not_allowed)
				(footprints allowed)
			)
			(placement
				(enabled no)
				(sheetname "")
			)
			(fill
				(thermal_gap 0.5)
				(thermal_bridge_width 0.5)
				(island_removal_mode 0)
			)
			(polygon
				(pts
					(xy 25.273 -76.073) (xy 25.273 -75.565) (xy 25.654 -75.565) (xy 25.654 -76.073)
				)
			)
		)
		(zone
			(layer "F.Cu")
			(hatch none 0.5)
			(connect_pads
				(clearance 0)
			)
			(min_thickness 0.25)
			(keepout
				(tracks allowed)
				(vias not_allowed)
				(pads allowed)
				(copperpour not_allowed)
				(footprints allowed)
			)
			(placement
				(enabled no)
				(sheetname "")
			)
			(fill
				(thermal_gap 0.5)
				(thermal_bridge_width 0.5)
				(island_removal_mode 0)
			)
			(polygon
				(pts
					(xy 25.654 -76.073) (xy 25.654 -75.565) (xy 25.273 -75.565) (xy 25.273 -76.073)
				)
			)
		)
	)
	(footprint ""
		(layer "F.Cu")
		(at 14.478 -86.741 180)
		(property "Reference" "R1D6"
			(at 0 0 180)
			(layer "F.SilkS")
			(hide yes)
			(effects
				(font
					(size 1.27 1.27)
				)
			)
		)
		(property "Value" ""
			(at 0 0 180)
			(layer "F.Fab")
			(effects
				(font
					(size 1.27 1.27)
				)
			)
		)
		(duplicate_pad_numbers_are_jumpers no)
		(fp_rect
			(start 0.2794 -0.1016)
			(end -0.2794 0.9906)
			(stroke
				(width 0)
				(type default)
			)
			(fill no)
			(layer "F.CrtYd")
		)
		(fp_line
			(start 0.2794 0.9906)
			(end 0.2794 -0.1016)
			(stroke
				(width 0.1)
				(type default)
			)
			(layer "F.Fab")
		)
		(fp_line
			(start 0.2794 -0.1016)
			(end -0.2794 -0.1016)
			(stroke
				(width 0.1)
				(type default)
			)
			(layer "F.Fab")
		)
		(fp_line
			(start -0.2794 0.9906)
			(end 0.2794 0.9906)
			(stroke
				(width 0.1)
				(type default)
			)
			(layer "F.Fab")
		)
		(fp_line
			(start -0.2794 -0.1016)
			(end -0.2794 0.9906)
			(stroke
				(width 0.1)
				(type default)
			)
			(layer "F.Fab")
		)
		(pad "1" smd rect
			(at 0 0 180)
			(size 0.508 0.508)
			(layers "F.Cu" "F.Mask" "F.Paste")
			(net "P3V3_STBY")
		)
		(pad "2" smd rect
			(at 0 0.889 180)
			(size 0.508 0.508)
			(layers "F.Cu" "F.Mask" "F.Paste")
			(net "IRQ_PVCCIN_CPU1_VRHOT_LVC3_R_N")
		)
		(zone
			(layer "F.Cu")
			(hatch none 0.5)
			(connect_pads
				(clearance 0)
			)
			(min_thickness 0.25)
			(keepout
				(tracks allowed)
				(vias not_allowed)
				(pads allowed)
				(copperpour not_allowed)
				(footprints allowed)
			)
			(placement
				(enabled no)
				(sheetname "")
			)
			(fill
				(thermal_gap 0.5)
				(thermal_bridge_width 0.5)
				(island_removal_mode 0)
			)
			(polygon
				(pts
					(xy 14.224 -86.995) (xy 14.732 -86.995) (xy 14.732 -87.376) (xy 14.224 -87.376)
				)
			)
		)
		(zone
			(layer "F.Cu")
			(hatch none 0.5)
			(connect_pads
				(clearance 0)
			)
			(min_thickness 0.25)
			(keepout
				(tracks not_allowed)
				(vias allowed)
				(pads allowed)
				(copperpour not_allowed)
				(footprints allowed)
			)
			(placement
				(enabled no)
				(sheetname "")
			)
			(fill
				(thermal_gap 0.5)
				(thermal_bridge_width 0.5)
				(island_removal_mode 0)
			)
			(polygon
				(pts
					(xy 14.224 -86.995) (xy 14.732 -86.995) (xy 14.732 -87.376) (xy 14.224 -87.376)
				)
			)
		)
	)
	(footprint ""
		(layer "F.Cu")
		(at 478.540572 -12.462256)
		(property "Reference" "R9G24"
			(at -0.8382 -0.67818 0)
			(unlocked yes)
			(layer "F.SilkS")
			(effects
				(font
					(size 0.4064 0.254)
					(thickness 0.1524)
				)
				(justify left)
			)
		)
		(property "Value" ""
			(at 0 0 0)
			(layer "F.Fab")
			(effects
				(font
					(size 1.27 1.27)
				)
			)
		)
		(duplicate_pad_numbers_are_jumpers no)
		(fp_poly
			(pts
				(xy -0.2794 -0.1016) (xy 0.2794 -0.1016) (xy 0.2794 0.9906) (xy -0.2794 0.9906)
			)
			(stroke
				(width 0)
				(type default)
			)
			(fill no)
			(layer "F.CrtYd")
		)
		(fp_line
			(start -0.2794 -0.1016)
			(end -0.2794 0.9906)
			(stroke
				(width 0.1)
				(type default)
			)
			(layer "F.Fab")
		)
		(fp_line
			(start -0.2794 0.9906)
			(end 0.2794 0.9906)
			(stroke
				(width 0.1)
				(type default)
			)
			(layer "F.Fab")
		)
		(fp_line
			(start 0.2794 -0.1016)
			(end -0.2794 -0.1016)
			(stroke
				(width 0.1)
				(type default)
			)
			(layer "F.Fab")
		)
		(fp_line
			(start 0.2794 0.9906)
			(end 0.2794 -0.1016)
			(stroke
				(width 0.1)
				(type default)
			)
			(layer "F.Fab")
		)
		(pad "1" smd rect
			(at 0 0)
			(size 0.508 0.508)
			(layers "F.Cu" "F.Mask" "F.Paste")
			(net "NIC_MDI_SPRV_RJ45_0_DP")
		)
		(pad "2" smd rect
			(at 0 0.889)
			(size 0.508 0.508)
			(layers "F.Cu" "F.Mask" "F.Paste")
			(net "NIC_MDI_SPRV_RJ45_0_R_DP")
		)
		(zone
			(layer "F.Cu")
			(hatch none 0.5)
			(connect_pads
				(clearance 0)
			)
			(min_thickness 0.25)
			(keepout
				(tracks allowed)
				(vias not_allowed)
				(pads allowed)
				(copperpour not_allowed)
				(footprints allowed)
			)
			(placement
				(enabled no)
				(sheetname "")
			)
			(fill
				(thermal_gap 0.5)
				(thermal_bridge_width 0.5)
				(island_removal_mode 0)
			)
			(polygon
				(pts
					(xy 478.286572 -12.208256) (xy 478.794572 -12.208256) (xy 478.794572 -11.827256) (xy 478.286572 -11.827256)
				)
			)
		)
		(zone
			(layer "F.Cu")
			(hatch none 0.5)
			(connect_pads
				(clearance 0)
			)
			(min_thickness 0.25)
			(keepout
				(tracks not_allowed)
				(vias allowed)
				(pads allowed)
				(copperpour not_allowed)
				(footprints allowed)
			)
			(placement
				(enabled no)
				(sheetname "")
			)
			(fill
				(thermal_gap 0.5)
				(thermal_bridge_width 0.5)
				(island_removal_mode 0)
			)
			(polygon
				(pts
					(xy 478.286572 -11.827256) (xy 478.794572 -11.827256) (xy 478.794572 -12.208256) (xy 478.286572 -12.208256)
				)
			)
		)
	)
	(footprint ""
		(layer "F.Cu")
		(at 420.751 -22.733)
		(property "Reference" "R1U14"
			(at 0 0 0)
			(layer "F.SilkS")
			(hide yes)
			(effects
				(font
					(size 1.27 1.27)
				)
			)
		)
		(property "Value" ""
			(at 0 0 0)
			(layer "F.Fab")
			(effects
				(font
					(size 1.27 1.27)
				)
			)
		)
		(duplicate_pad_numbers_are_jumpers no)
		(fp_poly
			(pts
				(xy -0.2794 -0.1016) (xy 0.2794 -0.1016) (xy 0.2794 0.9906) (xy -0.2794 0.9906)
			)
			(stroke
				(width 0)
				(type default)
			)
			(fill no)
			(layer "F.CrtYd")
		)
		(fp_line
			(start -0.2794 -0.1016)
			(end -0.2794 0.9906)
			(stroke
				(width 0.1)
				(type default)
			)
			(layer "F.Fab")
		)
		(fp_line
			(start -0.2794 0.9906)
			(end 0.2794 0.9906)
			(stroke
				(width 0.1)
				(type default)
			)
			(layer "F.Fab")
		)
		(fp_line
			(start 0.2794 -0.1016)
			(end -0.2794 -0.1016)
			(stroke
				(width 0.1)
				(type default)
			)
			(layer "F.Fab")
		)
		(fp_line
			(start 0.2794 0.9906)
			(end 0.2794 -0.1016)
			(stroke
				(width 0.1)
				(type default)
			)
			(layer "F.Fab")
		)
		(pad "1" smd rect
			(at 0 0)
			(size 0.508 0.508)
			(layers "F.Cu" "F.Mask" "F.Paste")
			(net "SGPIO_BMC_CLK_R")
		)
		(pad "2" smd rect
			(at 0 0.889)
			(size 0.508 0.508)
			(layers "F.Cu" "F.Mask" "F.Paste")
			(net "SGPIO_BMC_CLK")
		)
		(zone
			(layer "F.Cu")
			(hatch none 0.5)
			(connect_pads
				(clearance 0)
			)
			(min_thickness 0.25)
			(keepout
				(tracks allowed)
				(vias not_allowed)
				(pads allowed)
				(copperpour not_allowed)
				(footprints allowed)
			)
			(placement
				(enabled no)
				(sheetname "")
			)
			(fill
				(thermal_gap 0.5)
				(thermal_bridge_width 0.5)
				(island_removal_mode 0)
			)
			(polygon
				(pts
					(xy 420.497 -22.479) (xy 421.005 -22.479) (xy 421.005 -22.098) (xy 420.497 -22.098)
				)
			)
		)
		(zone
			(layer "F.Cu")
			(hatch none 0.5)
			(connect_pads
				(clearance 0)
			)
			(min_thickness 0.25)
			(keepout
				(tracks not_allowed)
				(vias allowed)
				(pads allowed)
				(copperpour not_allowed)
				(footprints allowed)
			)
			(placement
				(enabled no)
				(sheetname "")
			)
			(fill
				(thermal_gap 0.5)
				(thermal_bridge_width 0.5)
				(island_removal_mode 0)
			)
			(polygon
				(pts
					(xy 420.497 -22.098) (xy 421.005 -22.098) (xy 421.005 -22.479) (xy 420.497 -22.479)
				)
			)
		)
	)
	(footprint ""
		(layer "F.Cu")
		(at 20.447 -80.90408 180)
		(property "Reference" "R1D23"
			(at 0 0 180)
			(layer "F.SilkS")
			(hide yes)
			(effects
				(font
					(size 1.27 1.27)
				)
			)
		)
		(property "Value" ""
			(at 0 0 180)
			(layer "F.Fab")
			(effects
				(font
					(size 1.27 1.27)
				)
			)
		)
		(duplicate_pad_numbers_are_jumpers no)
		(fp_poly
			(pts
				(xy -0.2794 -0.1016) (xy 0.2794 -0.1016) (xy 0.2794 0.9906) (xy -0.2794 0.9906)
			)
			(stroke
				(width 0)
				(type default)
			)
			(fill no)
			(layer "F.CrtYd")
		)
		(fp_line
			(start 0.2794 0.9906)
			(end 0.2794 -0.1016)
			(stroke
				(width 0.1)
				(type default)
			)
			(layer "F.Fab")
		)
		(fp_line
			(start 0.2794 -0.1016)
			(end -0.2794 -0.1016)
			(stroke
				(width 0.1)
				(type default)
			)
			(layer "F.Fab")
		)
		(fp_line
			(start -0.2794 0.9906)
			(end 0.2794 0.9906)
			(stroke
				(width 0.1)
				(type default)
			)
			(layer "F.Fab")
		)
		(fp_line
			(start -0.2794 -0.1016)
			(end -0.2794 0.9906)
			(stroke
				(width 0.1)
				(type default)
			)
			(layer "F.Fab")
		)
		(pad "1" smd rect
			(at 0 0 180)
			(size 0.508 0.508)
			(layers "F.Cu" "F.Mask" "F.Paste")
			(net "P3V3_STBY")
		)
		(pad "2" smd rect
			(at 0 0.889 180)
			(size 0.508 0.508)
			(layers "F.Cu" "F.Mask" "F.Paste")
			(net "IRQ_OC_DETECT_N")
		)
		(zone
			(layer "F.Cu")
			(hatch none 0.5)
			(connect_pads
				(clearance 0)
			)
			(min_thickness 0.25)
			(keepout
				(tracks not_allowed)
				(vias allowed)
				(pads allowed)
				(copperpour not_allowed)
				(footprints allowed)
			)
			(placement
				(enabled no)
				(sheetname "")
			)
			(fill
				(thermal_gap 0.5)
				(thermal_bridge_width 0.5)
				(island_removal_mode 0)
			)
			(polygon
				(pts
					(xy 20.701 -81.53908) (xy 20.193 -81.53908) (xy 20.193 -81.15808) (xy 20.701 -81.15808)
				)
			)
		)
		(zone
			(layer "F.Cu")
			(hatch none 0.5)
			(connect_pads
				(clearance 0)
			)
			(min_thickness 0.25)
			(keepout
				(tracks allowed)
				(vias not_allowed)
				(pads allowed)
				(copperpour not_allowed)
				(footprints allowed)
			)
			(placement
				(enabled no)
				(sheetname "")
			)
			(fill
				(thermal_gap 0.5)
				(thermal_bridge_width 0.5)
				(island_removal_mode 0)
			)
			(polygon
				(pts
					(xy 20.701 -81.15808) (xy 20.193 -81.15808) (xy 20.193 -81.53908) (xy 20.701 -81.53908)
				)
			)
		)
	)
	(footprint ""
		(layer "F.Cu")
		(at 403.112986 -81.548986 -90)
		(property "Reference" "C2P9"
			(at 0 0 270)
			(layer "F.SilkS")
			(hide yes)
			(effects
				(font
					(size 1.27 1.27)
				)
			)
		)
		(property "Value" ""
			(at 0 0 270)
			(layer "F.Fab")
			(effects
				(font
					(size 1.27 1.27)
				)
			)
		)
		(duplicate_pad_numbers_are_jumpers no)
		(fp_poly
			(pts
				(xy 0.3048 -0.1016) (xy 0.3048 0.9906) (xy -0.3048 0.9906) (xy -0.3048 -0.1016)
			)
			(stroke
				(width 0)
				(type default)
			)
			(fill no)
			(layer "F.CrtYd")
		)
		(fp_line
			(start -0.3048 0.9906)
			(end 0.3048 0.9906)
			(stroke
				(width 0.1)
				(type default)
			)
			(layer "F.Fab")
		)
		(fp_line
			(start 0.3048 0.9906)
			(end 0.3048 -0.1016)
			(stroke
				(width 0.1)
				(type default)
			)
			(layer "F.Fab")
		)
		(fp_line
			(start -0.3048 -0.1016)
			(end -0.3048 0.9906)
			(stroke
				(width 0.1)
				(type default)
			)
			(layer "F.Fab")
		)
		(fp_line
			(start 0.3048 -0.1016)
			(end -0.3048 -0.1016)
			(stroke
				(width 0.1)
				(type default)
			)
			(layer "F.Fab")
		)
		(pad "1" smd rect
			(at 0 0 270)
			(size 0.508 0.508)
			(layers "F.Cu" "F.Mask" "F.Paste")
			(net "P3V3_STBY")
		)
		(pad "2" smd rect
			(at 0 0.889 270)
			(size 0.508 0.508)
			(layers "F.Cu" "F.Mask" "F.Paste")
			(net "GND")
		)
		(zone
			(layer "F.Cu")
			(hatch none 0.5)
			(connect_pads
				(clearance 0)
			)
			(min_thickness 0.25)
			(keepout
				(tracks not_allowed)
				(vias allowed)
				(pads allowed)
				(copperpour not_allowed)
				(footprints allowed)
			)
			(placement
				(enabled no)
				(sheetname "")
			)
			(fill
				(thermal_gap 0.5)
				(thermal_bridge_width 0.5)
				(island_removal_mode 0)
			)
			(polygon
				(pts
					(xy 402.477986 -81.802986) (xy 402.477986 -81.294986) (xy 402.858986 -81.294986) (xy 402.858986 -81.802986)
				)
			)
		)
		(zone
			(layer "F.Cu")
			(hatch none 0.5)
			(connect_pads
				(clearance 0)
			)
			(min_thickness 0.25)
			(keepout
				(tracks allowed)
				(vias not_allowed)
				(pads allowed)
				(copperpour not_allowed)
				(footprints allowed)
			)
			(placement
				(enabled no)
				(sheetname "")
			)
			(fill
				(thermal_gap 0.5)
				(thermal_bridge_width 0.5)
				(island_removal_mode 0)
			)
			(polygon
				(pts
					(xy 402.858986 -81.802986) (xy 402.858986 -81.294986) (xy 402.477986 -81.294986) (xy 402.477986 -81.802986)
				)
			)
		)
	)
	(footprint ""
		(layer "F.Cu")
		(at 181.1147 -75.68565 -90)
		(property "Reference" "C4D19"
			(at 0 0 270)
			(layer "F.SilkS")
			(hide yes)
			(effects
				(font
					(size 1.27 1.27)
				)
			)
		)
		(property "Value" ""
			(at 0 0 270)
			(layer "F.Fab")
			(effects
				(font
					(size 1.27 1.27)
				)
			)
		)
		(duplicate_pad_numbers_are_jumpers no)
		(fp_rect
			(start 0.3048 0.9906)
			(end -0.3048 -0.1016)
			(stroke
				(width 0)
				(type default)
			)
			(fill no)
			(layer "F.CrtYd")
		)
		(fp_line
			(start -0.3048 0.9906)
			(end 0.3048 0.9906)
			(stroke
				(width 0.1)
				(type default)
			)
			(layer "F.Fab")
		)
		(fp_line
			(start 0.3048 0.9906)
			(end 0.3048 -0.1016)
			(stroke
				(width 0.1)
				(type default)
			)
			(layer "F.Fab")
		)
		(fp_line
			(start -0.3048 -0.1016)
			(end -0.3048 0.9906)
			(stroke
				(width 0.1)
				(type default)
			)
			(layer "F.Fab")
		)
		(fp_line
			(start 0.3048 -0.1016)
			(end -0.3048 -0.1016)
			(stroke
				(width 0.1)
				(type default)
			)
			(layer "F.Fab")
		)
		(pad "1" smd rect
			(at 0 0 270)
			(size 0.508 0.508)
			(layers "F.Cu" "F.Mask" "F.Paste")
			(net "VR_PVCCIN_CPU0_VDD")
		)
		(pad "2" smd rect
			(at 0 0.889 270)
			(size 0.508 0.508)
			(layers "F.Cu" "F.Mask" "F.Paste")
			(net "GND")
		)
		(zone
			(layer "F.Cu")
			(hatch none 0.5)
			(connect_pads
				(clearance 0)
			)
			(min_thickness 0.25)
			(keepout
				(tracks allowed)
				(vias not_allowed)
				(pads allowed)
				(copperpour not_allowed)
				(footprints allowed)
			)
			(placement
				(enabled no)
				(sheetname "")
			)
			(fill
				(thermal_gap 0.5)
				(thermal_bridge_width 0.5)
				(island_removal_mode 0)
			)
			(polygon
				(pts
					(xy 180.4797 -75.43165) (xy 180.8607 -75.43165) (xy 180.8607 -75.93965) (xy 180.4797 -75.93965)
				)
			)
		)
		(zone
			(layer "F.Cu")
			(hatch none 0.5)
			(connect_pads
				(clearance 0)
			)
			(min_thickness 0.25)
			(keepout
				(tracks not_allowed)
				(vias allowed)
				(pads allowed)
				(copperpour not_allowed)
				(footprints allowed)
			)
			(placement
				(enabled no)
				(sheetname "")
			)
			(fill
				(thermal_gap 0.5)
				(thermal_bridge_width 0.5)
				(island_removal_mode 0)
			)
			(polygon
				(pts
					(xy 180.4797 -75.43165) (xy 180.8607 -75.43165) (xy 180.8607 -75.93965) (xy 180.4797 -75.93965)
				)
			)
		)
	)
)
